# T6G (Grand Teton) — schematic netlist excerpt (pin names and nets, part order shuffled) for the footprints in the layout excerpt that follows; sources: Cadence DE-HDL packaged netlist, KiCad conversion of 04192023_DAF0TMB3IC0_F0TG_MB_C_brd_V02_OCP.brd

R3515  Q_RES  49.9 1% CHIP  pkg 0402LF  page 128 : A = FM_SWB_PWR_EN_R1_BUF ; B = FM_SWB_PWR_EN_R_BUF
PC606  Q_CAP  2.2UF 10V 10% X6S  pkg C0402  page 199 : A = PVDDCR_SOC_P0_VCC3 ; B = GND

(kicad_pcb
	(version 20260206)
	(generator "pcbnew")
	(generator_version "10.0")
	(general
		(thickness 1.6)
		(legacy_teardrops no)
	)
	(paper "A4")
	(title_block
		(title "04192023_DAF0TMB3IC0_F0TG_MB_C_brd_V02_OCP.brd")
		(comment 1 "Grand Teton / footprints 2407-2408 of 8354")
	)
	(layers
		(0 "F.Cu" signal "TOP")
		(4 "In1.Cu" signal "GND")
		(6 "In2.Cu" signal "IN1")
		(8 "In3.Cu" signal "GND1")
		(10 "In4.Cu" signal "IN2")
		(12 "In5.Cu" signal "GND2")
		(14 "In6.Cu" signal "IN3")
		(16 "In7.Cu" signal "GND3")
		(18 "In8.Cu" signal "VCC")
		(20 "In9.Cu" signal "VCC1")
		(22 "In10.Cu" signal "GND4")
		(24 "In11.Cu" signal "IN4")
		(26 "In12.Cu" signal "GND5")
		(28 "In13.Cu" signal "IN5")
		(30 "In14.Cu" signal "GND6")
		(32 "In15.Cu" signal "IN6")
		(34 "In16.Cu" signal "GND7")
		(2 "B.Cu" signal "BOTTOM")
		(9 "F.Adhes" user "F.Adhesive")
		(11 "B.Adhes" user "B.Adhesive")
		(13 "F.Paste" user "Package Geometry/Pastemask Top")
		(15 "B.Paste" user "Package Geometry/Pastemask Bottom")
		(5 "F.SilkS" user "Ref Des/Silkscreen Top")
		(7 "B.SilkS" user "Ref Des/Silkscreen Bottom")
		(1 "F.Mask" user "Board Geometry/Soldermask Top")
		(3 "B.Mask" user "Board Geometry/Soldermask Bottom")
		(17 "Dwgs.User" user "User.Drawings")
		(19 "Cmts.User" user "User.Comments")
		(21 "Eco1.User" user "User.Eco1")
		(23 "Eco2.User" user "User.Eco2")
		(25 "Edge.Cuts" user "Board Geometry/Outline")
		(27 "Margin" user)
		(31 "F.CrtYd" user "Package Geometry/Place Bound Top")
		(29 "B.CrtYd" user "Package Geometry/Place Bound Bottom")
		(35 "F.Fab" user "Ref Des/Assembly Top")
		(33 "B.Fab" user "Ref Des/Assembly Bottom")
	)
	(footprint ""
		(layer "F.Cu")
		(at 41.33596 -434.086 -90)
		(property "Reference" "R3515"
			(at 0 0 270)
			(layer "F.SilkS")
			(hide yes)
			(effects
				(font
					(size 1.27 1.27)
				)
			)
		)
		(property "Value" ""
			(at 0 0 270)
			(layer "F.Fab")
			(effects
				(font
					(size 1.27 1.27)
				)
			)
		)
		(duplicate_pad_numbers_are_jumpers no)
		(fp_line
			(start -0.7874 0.4064)
			(end -0.7874 -0.4064)
			(stroke
				(width 0.1524)
				(type default)
			)
			(layer "F.SilkS")
		)
		(fp_line
			(start 0.7874 0.4064)
			(end -0.7874 0.4064)
			(stroke
				(width 0.1524)
				(type default)
			)
			(layer "F.SilkS")
		)
		(fp_line
			(start -0.7874 -0.4064)
			(end 0.7874 -0.4064)
			(stroke
				(width 0.1524)
				(type default)
			)
			(layer "F.SilkS")
		)
		(fp_line
			(start 0.7874 -0.4064)
			(end 0.7874 0.4064)
			(stroke
				(width 0.1524)
				(type default)
			)
			(layer "F.SilkS")
		)
		(fp_line
			(start -0.67945 0.3048)
			(end -0.67945 -0.305054)
			(stroke
				(width 0.1)
				(type default)
			)
			(layer "F.Fab")
		)
		(fp_line
			(start -0.12065 0.3048)
			(end -0.67945 0.3048)
			(stroke
				(width 0.1)
				(type default)
			)
			(layer "F.Fab")
		)
		(fp_line
			(start 0.120396 0.3048)
			(end 0.120396 0.2794)
			(stroke
				(width 0.1)
				(type default)
			)
			(layer "F.Fab")
		)
		(fp_line
			(start 0.67945 0.3048)
			(end 0.120396 0.3048)
			(stroke
				(width 0.1)
				(type default)
			)
			(layer "F.Fab")
		)
		(fp_line
			(start -0.12065 0.2794)
			(end -0.12065 0.3048)
			(stroke
				(width 0.1)
				(type default)
			)
			(layer "F.Fab")
		)
		(fp_line
			(start 0.120396 0.2794)
			(end -0.12065 0.2794)
			(stroke
				(width 0.1)
				(type default)
			)
			(layer "F.Fab")
		)
		(fp_line
			(start -0.12065 -0.2794)
			(end 0.12065 -0.2794)
			(stroke
				(width 0.1)
				(type default)
			)
			(layer "F.Fab")
		)
		(fp_line
			(start 0.12065 -0.2794)
			(end 0.12065 -0.3048)
			(stroke
				(width 0.1)
				(type default)
			)
			(layer "F.Fab")
		)
		(fp_line
			(start 0.12065 -0.3048)
			(end 0.67945 -0.3048)
			(stroke
				(width 0.1)
				(type default)
			)
			(layer "F.Fab")
		)
		(fp_line
			(start 0.67945 -0.3048)
			(end 0.67945 0.3048)
			(stroke
				(width 0.1)
				(type default)
			)
			(layer "F.Fab")
		)
		(fp_line
			(start -0.67945 -0.305054)
			(end -0.12065 -0.305054)
			(stroke
				(width 0.1)
				(type default)
			)
			(layer "F.Fab")
		)
		(fp_line
			(start -0.12065 -0.305054)
			(end -0.12065 -0.2794)
			(stroke
				(width 0.1)
				(type default)
			)
			(layer "F.Fab")
		)
		(pad "1" smd circle
			(at -0.40005 0 270)
			(size 0 0)
			(layers "F.Cu" "F.Mask" "F.Paste")
			(net "FM_SWB_PWR_EN_R1_BUF")
		)
		(pad "2" smd circle
			(at 0.40005 0 270)
			(size 0 0)
			(layers "F.Cu" "F.Mask" "F.Paste")
			(net "FM_SWB_PWR_EN_R_BUF")
		)
	)
	(footprint ""
		(layer "F.Cu")
		(at 418.212778 -161.102548 -90)
		(property "Reference" "PC606"
			(at 0 0 270)
			(layer "F.SilkS")
			(hide yes)
			(effects
				(font
					(size 1.27 1.27)
				)
			)
		)
		(property "Value" ""
			(at 0 0 270)
			(layer "F.Fab")
			(effects
				(font
					(size 1.27 1.27)
				)
			)
		)
		(duplicate_pad_numbers_are_jumpers no)
		(fp_line
			(start -0.7874 0.4064)
			(end -0.7874 -0.4064)
			(stroke
				(width 0.1524)
				(type default)
			)
			(layer "F.SilkS")
		)
		(fp_line
			(start -0.085852 0.4064)
			(end -0.7874 0.4064)
			(stroke
				(width 0.1524)
				(type default)
			)
			(layer "F.SilkS")
		)
		(fp_line
			(start 0.7874 0.4064)
			(end 0.396748 0.4064)
			(stroke
				(width 0.1524)
				(type default)
			)
			(layer "F.SilkS")
		)
		(fp_line
			(start -0.7874 -0.4064)
			(end 0.7874 -0.4064)
			(stroke
				(width 0.1524)
				(type default)
			)
			(layer "F.SilkS")
		)
		(fp_line
			(start 0.7874 -0.4064)
			(end 0.7874 0.4064)
			(stroke
				(width 0.1524)
				(type default)
			)
			(layer "F.SilkS")
		)
		(fp_line
			(start -0.67945 0.3048)
			(end -0.67945 -0.305054)
			(stroke
				(width 0.1)
				(type default)
			)
			(layer "F.Fab")
		)
		(fp_line
			(start -0.12065 0.3048)
			(end -0.67945 0.3048)
			(stroke
				(width 0.1)
				(type default)
			)
			(layer "F.Fab")
		)
		(fp_line
			(start 0.120396 0.3048)
			(end 0.120396 0.2794)
			(stroke
				(width 0.1)
				(type default)
			)
			(layer "F.Fab")
		)
		(fp_line
			(start 0.67945 0.3048)
			(end 0.120396 0.3048)
			(stroke
				(width 0.1)
				(type default)
			)
			(layer "F.Fab")
		)
		(fp_line
			(start -0.12065 0.2794)
			(end -0.12065 0.3048)
			(stroke
				(width 0.1)
				(type default)
			)
			(layer "F.Fab")
		)
		(fp_line
			(start 0.120396 0.2794)
			(end -0.12065 0.2794)
			(stroke
				(width 0.1)
				(type default)
			)
			(layer "F.Fab")
		)
		(fp_line
			(start -0.12065 -0.2794)
			(end 0.12065 -0.2794)
			(stroke
				(width 0.1)
				(type default)
			)
			(layer "F.Fab")
		)
		(fp_line
			(start 0.12065 -0.2794)
			(end 0.12065 -0.3048)
			(stroke
				(width 0.1)
				(type default)
			)
			(layer "F.Fab")
		)
		(fp_line
			(start 0.12065 -0.3048)
			(end 0.67945 -0.3048)
			(stroke
				(width 0.1)
				(type default)
			)
			(layer "F.Fab")
		)
		(fp_line
			(start 0.67945 -0.3048)
			(end 0.67945 0.3048)
			(stroke
				(width 0.1)
				(type default)
			)
			(layer "F.Fab")
		)
		(fp_line
			(start -0.67945 -0.305054)
			(end -0.12065 -0.305054)
			(stroke
				(width 0.1)
				(type default)
			)
			(layer "F.Fab")
		)
		(fp_line
			(start -0.12065 -0.305054)
			(end -0.12065 -0.2794)
			(stroke
				(width 0.1)
				(type default)
			)
			(layer "F.Fab")
		)
		(pad "1" smd circle
			(at -0.40005 0 270)
			(size 0 0)
			(layers "F.Cu" "F.Mask" "F.Paste")
			(net "PVDDCR_SOC_P0_VCC3")
		)
		(pad "2" smd circle
			(at 0.40005 0 270)
			(size 0 0)
			(layers "F.Cu" "F.Mask" "F.Paste")
			(net "GND")
		)
	)
)
